(kicad_pcb
	(version 20240108)
	(generator "pcbnew")
	(generator_version "8.0")
	(general
		(thickness 1.586)
		(legacy_teardrops no)
	)
	(paper "A4")
	(title_block
		(title "GMSL Serializer")
		(date "2024-11-27")
		(rev "1.1.1")
		(company "Antmicro Ltd")
		(comment 1 "www.antmicro.com")
		(comment 9 "footprints 63-67 of 117")
	)
	(layers
		(0 "F.Cu" signal)
		(1 "In1.Cu" power)
		(2 "In2.Cu" power)
		(31 "B.Cu" signal)
		(32 "B.Adhes" user "B.Adhesive")
		(33 "F.Adhes" user "F.Adhesive")
		(34 "B.Paste" user)
		(35 "F.Paste" user)
		(36 "B.SilkS" user "B.Silkscreen")
		(37 "F.SilkS" user "F.Silkscreen")
		(38 "B.Mask" user)
		(39 "F.Mask" user)
		(40 "Dwgs.User" user "User.Drawings")
		(41 "Cmts.User" user "User.Comments")
		(42 "Eco1.User" user "User.Eco1")
		(43 "Eco2.User" user "User.Eco2")
		(44 "Edge.Cuts" user)
		(45 "Margin" user)
		(46 "B.CrtYd" user "B.Courtyard")
		(47 "F.CrtYd" user "F.Courtyard")
		(48 "B.Fab" user)
		(49 "F.Fab" user)
	)
	(footprint "antmicro-footprints:TSOT23-6"
		(layer "F.Cu")
		(at 161.8 101 180)
		(property "Reference" "U2"
			(at 2.1 1.7 90)
			(layer "F.SilkS")
			(effects
				(font
					(size 0.7 0.7)
					(thickness 0.15)
				)
				(justify right bottom)
			)
		)
		(property "Value" "AP62301_TSOT"
			(at 0 2.6 0)
			(layer "F.Fab")
			(effects
				(font
					(size 0.7 0.7)
					(thickness 0.15)
				)
				(justify right bottom)
			)
		)
		(property "Footprint" "antmicro-footprints:TSOT23-6"
			(at 0 0 180)
			(layer "F.Fab")
			(hide yes)
			(effects
				(font
					(size 1.27 1.27)
					(thickness 0.15)
				)
			)
		)
		(property "Datasheet" "https://www.diodes.com/assets/Datasheets/AP62300_AP62301_AP62300T.pdf"
			(at 0 0 180)
			(layer "F.Fab")
			(hide yes)
			(effects
				(font
					(size 1.27 1.27)
					(thickness 0.15)
				)
			)
		)
		(property "Author" "Antmicro"
			(at 323.6 202 0)
			(layer "F.Fab")
			(hide yes)
			(effects
				(font
					(size 1 1)
					(thickness 0.15)
				)
			)
		)
		(property "License" "Apache-2.0"
			(at 323.6 202 0)
			(layer "F.Fab")
			(hide yes)
			(effects
				(font
					(size 1 1)
					(thickness 0.15)
				)
			)
		)
		(property "MPN" "AP62301WU-7"
			(at 323.6 202 0)
			(layer "F.Fab")
			(hide yes)
			(effects
				(font
					(size 1 1)
					(thickness 0.15)
				)
			)
		)
		(property "Manufacturer" "Diodes Incorporated"
			(at 323.6 202 0)
			(layer "F.Fab")
			(hide yes)
			(effects
				(font
					(size 1 1)
					(thickness 0.15)
				)
			)
		)
		(sheetname "Supply")
		(sheetfile "supply.kicad_sch")
		(attr smd)
		(fp_line
			(start 1 1.55)
			(end 1 1.4)
			(stroke
				(width 0.15)
				(type solid)
			)
			(layer "F.SilkS")
		)
		(fp_line
			(start 1 1.55)
			(end -1 1.55)
			(stroke
				(width 0.15)
				(type solid)
			)
			(layer "F.SilkS")
		)
		(fp_line
			(start 1 -1.497)
			(end 1 -1.375)
			(stroke
				(width 0.15)
				(type solid)
			)
			(layer "F.SilkS")
		)
		(fp_line
			(start 1 -1.497)
			(end -1 -1.5)
			(stroke
				(width 0.15)
				(type solid)
			)
			(layer "F.SilkS")
		)
		(fp_line
			(start -1 1.55)
			(end -1 1.4)
			(stroke
				(width 0.15)
				(type solid)
			)
			(layer "F.SilkS")
		)
		(fp_line
			(start -1 -1.5)
			(end -1 -1.375)
			(stroke
				(width 0.15)
				(type solid)
			)
			(layer "F.SilkS")
		)
		(fp_circle
			(center -1.44 -1.5)
			(end -1.39 -1.5)
			(stroke
				(width 0.15)
				(type solid)
			)
			(fill solid)
			(layer "F.SilkS")
		)
		(fp_rect
			(start 1.93 -1.7)
			(end -1.93 1.7)
			(stroke
				(width 0.05)
				(type solid)
			)
			(fill none)
			(layer "F.CrtYd")
		)
		(fp_line
			(start -0.45 -1.521)
			(end -0.876 -1.096)
			(stroke
				(width 0.15)
				(type solid)
			)
			(layer "F.Fab")
		)
		(fp_rect
			(start 0.875 1.528)
			(end -0.875 -1.525)
			(stroke
				(width 0.15)
				(type solid)
			)
			(fill none)
			(layer "F.Fab")
		)
		(fp_text user "${REFERENCE}"
			(at -1.93 3.8 0)
			(layer "F.Fab")
			(hide yes)
			(effects
				(font
					(size 0.7 0.7)
					(thickness 0.15)
				)
				(justify right bottom)
			)
		)
		(fp_text user "License: Apache-2.0"
			(at -1.93 6.199 0)
			(layer "F.Fab")
			(hide yes)
			(effects
				(font
					(size 0.7 0.7)
					(thickness 0.15)
				)
				(justify right bottom)
			)
		)
		(fp_text user "Author: Antmicro"
			(at -1.93 5 0)
			(layer "F.Fab")
			(hide yes)
			(effects
				(font
					(size 0.7 0.7)
					(thickness 0.15)
				)
				(justify right bottom)
			)
		)
		(pad "1" smd rect
			(at -1.301 -0.947 90)
			(size 0.7 1.2)
			(layers "F.Cu" "F.Paste" "F.Mask")
			(net 1 "GND")
			(pinfunction "GND")
			(pintype "power_in")
		)
		(pad "2" smd rect
			(at -1.301 0.004 90)
			(size 0.7 1.2)
			(layers "F.Cu" "F.Paste" "F.Mask")
			(net 6 "/Supply/SW_1V8")
			(pinfunction "SW")
			(pintype "power_out")
		)
		(pad "3" smd rect
			(at -1.301 0.954 90)
			(size 0.7 1.2)
			(layers "F.Cu" "F.Paste" "F.Mask")
			(net 2 "+12V")
			(pinfunction "VIN")
			(pintype "power_in")
		)
		(pad "4" smd rect
			(at 1.299 0.954 90)
			(size 0.7 1.2)
			(layers "F.Cu" "F.Paste" "F.Mask")
			(net 65 "/Supply/FB_1V8")
			(pinfunction "FB")
			(pintype "input")
		)
		(pad "5" smd rect
			(at 1.299 0.004 90)
			(size 0.7 1.2)
			(layers "F.Cu" "F.Paste" "F.Mask")
			(net 63 "/Supply/EN_1V8")
			(pinfunction "EN")
			(pintype "input")
		)
		(pad "6" smd rect
			(at 1.299 -0.947 90)
			(size 0.7 1.2)
			(layers "F.Cu" "F.Paste" "F.Mask")
			(net 5 "Net-(U2-BST)")
			(pinfunction "BST")
			(pintype "output")
		)
	)
	(footprint "antmicro-footprints:MP_Pad6mm_Drill3mm"
		(layer "F.Cu")
		(at 163.15 117.35)
		(property "Reference" "MP1"
			(at 0 -3.2 0)
			(layer "F.SilkS")
			(hide yes)
			(effects
				(font
					(size 0.7 0.7)
					(thickness 0.15)
				)
				(justify left bottom)
			)
		)
		(property "Value" "MP_Pad6mm_Drill3mm"
			(at 0 3.9 0)
			(layer "F.Fab")
			(effects
				(font
					(size 0.7 0.7)
					(thickness 0.15)
				)
				(justify left bottom)
			)
		)
		(property "Footprint" "antmicro-footprints:MP_Pad6mm_Drill3mm"
			(at 0 0 0)
			(layer "F.Fab")
			(hide yes)
			(effects
				(font
					(size 1.27 1.27)
					(thickness 0.15)
				)
			)
		)
		(property "Author" "Antmicro"
			(at 0 0 0)
			(layer "F.Fab")
			(hide yes)
			(effects
				(font
					(size 1 1)
					(thickness 0.15)
				)
			)
		)
		(property "License" "Apache-2.0"
			(at 0 0 0)
			(layer "F.Fab")
			(hide yes)
			(effects
				(font
					(size 1 1)
					(thickness 0.15)
				)
			)
		)
		(sheetname "Root")
		(sheetfile "gmsl-serializer.kicad_sch")
		(attr exclude_from_pos_files exclude_from_bom)
		(fp_circle
			(center 0 0)
			(end 3.25 0)
			(stroke
				(width 0.05)
				(type default)
			)
			(fill none)
			(layer "F.CrtYd")
		)
		(fp_text user "${REFERENCE}"
			(at -0.178 6.025 0)
			(layer "F.Fab")
			(hide yes)
			(effects
				(font
					(size 0.7 0.7)
					(thickness 0.15)
				)
				(justify left bottom)
			)
		)
		(fp_text user "License: Apache-2.0"
			(at -0.178 8.425 0)
			(layer "F.Fab")
			(hide yes)
			(effects
				(font
					(size 0.7 0.7)
					(thickness 0.15)
				)
				(justify left bottom)
			)
		)
		(fp_text user "Author: Antmicro"
			(at -0.178 7.225 0)
			(layer "F.Fab")
			(hide yes)
			(effects
				(font
					(size 0.7 0.7)
					(thickness 0.15)
				)
				(justify left bottom)
			)
		)
		(pad "1" thru_hole circle
			(at 0 0)
			(size 6 6)
			(drill 3)
			(layers "*.Cu" "*.Mask")
			(remove_unused_layers no)
			(net 1 "GND")
			(pintype "passive")
			(solder_paste_margin_ratio -1)
		)
	)
	(footprint "antmicro-footprints:C_0402_1005Metric"
		(layer "F.Cu")
		(at 147.91 95.77 -45)
		(descr "Capacitor SMD 0402")
		(tags "capacitor SMD 0402")
		(property "Reference" "C33"
			(at 0.947523 -2.375879 -45)
			(unlocked yes)
			(layer "F.SilkS")
			(effects
				(font
					(size 0.7 0.7)
					(thickness 0.15)
				)
				(justify right bottom)
			)
		)
		(property "Value" "C_10u_0402"
			(at -1.022927 2.155213 135)
			(layer "F.Fab")
			(effects
				(font
					(size 0.7 0.7)
					(thickness 0.15)
				)
				(justify right bottom)
			)
		)
		(property "Footprint" "antmicro-footprints:C_0402_1005Metric"
			(at 0 0 -45)
			(layer "F.Fab")
			(hide yes)
			(effects
				(font
					(size 1.27 1.27)
					(thickness 0.15)
				)
			)
		)
		(property "Datasheet" "https://www.yageo.com/en/Chart/Download/pdf/CC0402MRX5R5BB106"
			(at 0 0 -45)
			(layer "F.Fab")
			(hide yes)
			(effects
				(font
					(size 1.27 1.27)
					(thickness 0.15)
				)
			)
		)
		(property "Author" "Antmicro"
			(at -24.39778 132.638547 0)
			(layer "F.Fab")
			(hide yes)
			(effects
				(font
					(size 1 1)
					(thickness 0.15)
				)
			)
		)
		(property "Dielectric" ""
			(at -24.39778 132.638547 0)
			(layer "F.Fab")
			(hide yes)
			(effects
				(font
					(size 1 1)
					(thickness 0.15)
				)
			)
		)
		(property "License" "Apache-2.0"
			(at -24.39778 132.638547 0)
			(layer "F.Fab")
			(hide yes)
			(effects
				(font
					(size 1 1)
					(thickness 0.15)
				)
			)
		)
		(property "MPN" "CC0402MRX5R5BB106"
			(at -24.39778 132.638547 0)
			(layer "F.Fab")
			(hide yes)
			(effects
				(font
					(size 1 1)
					(thickness 0.15)
				)
			)
		)
		(property "Manufacturer" "YAGEO"
			(at -24.39778 132.638547 0)
			(layer "F.Fab")
			(hide yes)
			(effects
				(font
					(size 1 1)
					(thickness 0.15)
				)
			)
		)
		(property "Val" "10u"
			(at -24.39778 132.638547 0)
			(layer "F.Fab")
			(hide yes)
			(effects
				(font
					(size 1 1)
					(thickness 0.15)
				)
			)
		)
		(property "Voltage" ""
			(at -24.39778 132.638547 0)
			(layer "F.Fab")
			(hide yes)
			(effects
				(font
					(size 1 1)
					(thickness 0.15)
				)
			)
		)
		(sheetname "Serializer")
		(sheetfile "serializer.kicad_sch")
		(attr smd)
		(fp_poly
			(pts
				(xy -0.925 -0.47) (xy 0.925 -0.47) (xy 0.925 0.47) (xy -0.925 0.47)
			)
			(stroke
				(width 0.05)
				(type default)
			)
			(fill none)
			(layer "F.CrtYd")
		)
		(fp_line
			(start -0.494 0.248)
			(end -0.494 -0.25)
			(stroke
				(width 0.15)
				(type solid)
			)
			(layer "F.Fab")
		)
		(fp_line
			(start -0.494 -0.25)
			(end 0.504 -0.25)
			(stroke
				(width 0.15)
				(type solid)
			)
			(layer "F.Fab")
		)
		(fp_line
			(start 0.504 0.248)
			(end -0.494 0.248)
			(stroke
				(width 0.15)
				(type solid)
			)
			(layer "F.Fab")
		)
		(fp_line
			(start 0.504 -0.25)
			(end 0.504 0.248)
			(stroke
				(width 0.15)
				(type solid)
			)
			(layer "F.Fab")
		)
		(fp_text user "${REFERENCE}"
			(at -0.939 4.599 135)
			(layer "F.Fab")
			(hide yes)
			(effects
				(font
					(size 0.7 0.7)
					(thickness 0.15)
				)
				(justify right bottom)
			)
		)
		(fp_text user "License: Apache-2.0"
			(at -0.939 5.799 135)
			(layer "F.Fab")
			(hide yes)
			(effects
				(font
					(size 0.7 0.7)
					(thickness 0.15)
				)
				(justify right bottom)
			)
		)
		(fp_text user "Author: Antmicro"
			(at -0.939 3.399 135)
			(layer "F.Fab")
			(hide yes)
			(effects
				(font
					(size 0.7 0.7)
					(thickness 0.15)
				)
				(justify right bottom)
			)
		)
		(pad "1" smd roundrect
			(at -0.48 0 315)
			(size 0.59 0.64)
			(layers "F.Cu" "F.Paste" "F.Mask")
			(roundrect_rratio 0.25)
			(net 1 "GND")
			(pintype "passive")
		)
		(pad "2" smd roundrect
			(at 0.48 0 315)
			(size 0.59 0.64)
			(layers "F.Cu" "F.Paste" "F.Mask")
			(roundrect_rratio 0.25)
			(net 10 "+3V3")
			(pintype "passive")
		)
	)
	(footprint "antmicro-footprints:L_Bourns-SRP3212A"
		(layer "F.Cu")
		(at 142.25 86.910142)
		(property "Reference" "L7"
			(at -2.95 2.469858 0)
			(layer "F.SilkS")
			(effects
				(font
					(size 0.7 0.7)
					(thickness 0.15)
				)
				(justify left bottom)
			)
		)
		(property "Value" "L_3u3_3.1A_Bourns-SRP3212A"
			(at 1.49 1.5 0)
			(layer "F.Fab")
			(effects
				(font
					(size 0.7 0.7)
					(thickness 0.15)
				)
				(justify left bottom)
			)
		)
		(property "Footprint" "antmicro-footprints:L_Bourns-SRP3212A"
			(at 0 0 0)
			(layer "F.Fab")
			(hide yes)
			(effects
				(font
					(size 1.27 1.27)
					(thickness 0.15)
				)
			)
		)
		(property "Datasheet" "https://www.mouser.com/datasheet/2/54/SRP3212A-3011944.pdf"
			(at 0 0 0)
			(layer "F.Fab")
			(hide yes)
			(effects
				(font
					(size 1.27 1.27)
					(thickness 0.15)
				)
			)
		)
		(property "Val" "3u3/3.1A"
			(at 0 0 0)
			(unlocked yes)
			(layer "F.Fab")
			(hide yes)
			(effects
				(font
					(size 1 1)
					(thickness 0.15)
				)
			)
		)
		(property "Manufacturer" "Bourns"
			(at 0 0 0)
			(unlocked yes)
			(layer "F.Fab")
			(hide yes)
			(effects
				(font
					(size 1 1)
					(thickness 0.15)
				)
			)
		)
		(property "MPN" "SRP3212-3R3M"
			(at 0 0 0)
			(unlocked yes)
			(layer "F.Fab")
			(hide yes)
			(effects
				(font
					(size 1 1)
					(thickness 0.15)
				)
			)
		)
		(property "ISat" "3.4 A"
			(at 0 0 0)
			(unlocked yes)
			(layer "F.Fab")
			(hide yes)
			(effects
				(font
					(size 1 1)
					(thickness 0.15)
				)
			)
		)
		(property "IMax" "3.1 A"
			(at 0 0 0)
			(unlocked yes)
			(layer "F.Fab")
			(hide yes)
			(effects
				(font
					(size 1 1)
					(thickness 0.15)
				)
			)
		)
		(property "Size" "3.2x2.5"
			(at 0 0 0)
			(unlocked yes)
			(layer "F.Fab")
			(hide yes)
			(effects
				(font
					(size 1 1)
					(thickness 0.15)
				)
			)
		)
		(property "Author" "Antmicro"
			(at 0 0 0)
			(unlocked yes)
			(layer "F.Fab")
			(hide yes)
			(effects
				(font
					(size 1 1)
					(thickness 0.15)
				)
			)
		)
		(property "License" "Apache-2.0"
			(at 0 0 0)
			(unlocked yes)
			(layer "F.Fab")
			(hide yes)
			(effects
				(font
					(size 1 1)
					(thickness 0.15)
				)
			)
		)
		(sheetname "Supply")
		(sheetfile "supply.kicad_sch")
		(attr smd)
		(fp_line
			(start -0.4 -1.25)
			(end 0.399 -1.25)
			(stroke
				(width 0.15)
				(type solid)
			)
			(layer "F.SilkS")
		)
		(fp_line
			(start -0.4 1.249)
			(end 0.399 1.249)
			(stroke
				(width 0.15)
				(type solid)
			)
			(layer "F.SilkS")
		)
		(fp_rect
			(start -2.1 -1.65)
			(end 2.1 1.65)
			(stroke
				(width 0.05)
				(type solid)
			)
			(fill none)
			(layer "F.CrtYd")
		)
		(fp_rect
			(start -1.609 -1.26)
			(end 1.609 1.26)
			(stroke
				(width 0.15)
				(type solid)
			)
			(fill none)
			(layer "F.Fab")
		)
		(fp_text user "${REFERENCE}"
			(at -2.1 4.8 0)
			(layer "F.Fab")
			(hide yes)
			(effects
				(font
					(size 0.7 0.7)
					(thickness 0.15)
				)
				(justify left bottom)
			)
		)
		(fp_text user "Author: Antmicro"
			(at -2.1 6 0)
			(layer "F.Fab")
			(hide yes)
			(effects
				(font
					(size 0.7 0.7)
					(thickness 0.15)
				)
				(justify left bottom)
			)
		)
		(fp_text user "License: Apache-2.0"
			(at -2.1 7.2 0)
			(layer "F.Fab")
			(hide yes)
			(effects
				(font
					(size 0.7 0.7)
					(thickness 0.15)
				)
				(justify left bottom)
			)
		)
		(pad "1" smd roundrect
			(at -1.175 0)
			(size 1.35 2.8)
			(layers "F.Cu" "F.Paste" "F.Mask")
			(roundrect_rratio 0.1)
			(net 72 "/Supply/SW_3V3")
			(pintype "passive")
		)
		(pad "2" smd roundrect
			(at 1.175 0)
			(size 1.35 2.8)
			(layers "F.Cu" "F.Paste" "F.Mask")
			(roundrect_rratio 0.1)
			(net 94 "/Supply/OUT_3V3")
			(pintype "passive")
		)
	)
	(footprint "antmicro-footprints:R_0402_1005Metric"
		(layer "F.Cu")
		(at 149.05 113.2 -90)
		(descr "Resistor SMD 0402")
		(tags "resistor SMD 0402")
		(property "Reference" "R38"
			(at -1.1 -1.2 90)
			(layer "F.SilkS")
			(effects
				(font
					(size 0.7 0.7)
					(thickness 0.15)
				)
				(justify right bottom)
			)
		)
		(property "Value" "R_100k_0402"
			(at -1.011843 1.772047 90)
			(layer "F.Fab")
			(effects
				(font
					(size 0.7 0.7)
					(thickness 0.15)
				)
				(justify right bottom)
			)
		)
		(property "Footprint" "antmicro-footprints:R_0402_1005Metric"
			(at 0 0 -90)
			(layer "F.Fab")
			(hide yes)
			(effects
				(font
					(size 1.27 1.27)
					(thickness 0.15)
				)
			)
		)
		(property "Datasheet" "https://www.bourns.com/docs/product-datasheets/cr.pdf"
			(at 0 0 -90)
			(layer "F.Fab")
			(hide yes)
			(effects
				(font
					(size 1.27 1.27)
					(thickness 0.15)
				)
			)
		)
		(property "Author" "Antmicro"
			(at 35.85 262.25 0)
			(layer "F.Fab")
			(hide yes)
			(effects
				(font
					(size 1 1)
					(thickness 0.15)
				)
			)
		)
		(property "License" "Apache-2.0"
			(at 35.85 262.25 0)
			(layer "F.Fab")
			(hide yes)
			(effects
				(font
					(size 1 1)
					(thickness 0.15)
				)
			)
		)
		(property "MPN" "CR0402-FX-1003GLF"
			(at 35.85 262.25 0)
			(layer "F.Fab")
			(hide yes)
			(effects
				(font
					(size 1 1)
					(thickness 0.15)
				)
			)
		)
		(property "Manufacturer" "Bourns"
			(at 35.85 262.25 0)
			(layer "F.Fab")
			(hide yes)
			(effects
				(font
					(size 1 1)
					(thickness 0.15)
				)
			)
		)
		(property "Tolerance" "1%"
			(at 35.85 262.25 0)
			(layer "F.Fab")
			(hide yes)
			(effects
				(font
					(size 1 1)
					(thickness 0.15)
				)
			)
		)
		(property "Val" "100k"
			(at 35.85 262.25 0)
			(layer "F.Fab")
			(hide yes)
			(effects
				(font
					(size 1 1)
					(thickness 0.15)
				)
			)
		)
		(sheetname "Supply")
		(sheetfile "supply.kicad_sch")
		(attr smd)
		(fp_rect
			(start -0.925 -0.47)
			(end 0.925 0.47)
			(stroke
				(width 0.05)
				(type default)
			)
			(fill none)
			(layer "F.CrtYd")
		)
		(fp_rect
			(start -0.5 -0.25)
			(end 0.5 0.25)
			(stroke
				(width 0.15)
				(type solid)
			)
			(fill none)
			(layer "F.Fab")
		)
		(fp_text user "Author: Antmicro"
			(at -0.95 4.169 90)
			(layer "F.Fab")
			(hide yes)
			(effects
				(font
					(size 0.7 0.7)
					(thickness 0.15)
				)
				(justify right bottom)
			)
		)
		(fp_text user "${REFERENCE}"
			(at -0.95 3.168 90)
			(layer "F.Fab")
			(hide yes)
			(effects
				(font
					(size 0.7 0.7)
					(thickness 0.15)
				)
				(justify right bottom)
			)
		)
		(fp_text user "License: Apache-2.0"
			(at -0.95 5.169 90)
			(layer "F.Fab")
			(hide yes)
			(effects
				(font
					(size 0.7 0.7)
					(thickness 0.15)
				)
				(justify right bottom)
			)
		)
		(pad "1" smd roundrect
			(at -0.48 0 270)
			(size 0.59 0.64)
			(layers "F.Cu" "F.Paste" "F.Mask")
			(roundrect_rratio 0.25)
			(net 1 "GND")
			(pintype "passive")
		)
		(pad "2" smd roundrect
			(at 0.48 0 270)
			(size 0.59 0.64)
			(layers "F.Cu" "F.Paste" "F.Mask")
			(roundrect_rratio 0.25)
			(net 11 "+1V8")
			(pintype "passive")
		)
	)
)
